(kicad_pcb
	(version 20241229)
	(generator "pcbnew")
	(generator_version "9.0")
	(general
		(thickness 1.61)
		(legacy_teardrops no)
	)
	(paper "A3")
	(title_block
		(title "SO-DIMM DDR5 Tester")
		(date "2025-11-26")
		(rev "1.3.0")
		(comment 9 "footprints 344-349 of 627")
	)
	(layers
		(0 "F.Cu" signal)
		(4 "In1.Cu" power)
		(6 "In2.Cu" mixed)
		(8 "In3.Cu" power)
		(10 "In4.Cu" mixed)
		(12 "In5.Cu" power)
		(14 "In6.Cu" mixed)
		(16 "In7.Cu" power)
		(18 "In8.Cu" power)
		(20 "In9.Cu" mixed)
		(22 "In10.Cu" power)
		(2 "B.Cu" signal)
		(9 "F.Adhes" user "F.Adhesive")
		(11 "B.Adhes" user "B.Adhesive")
		(13 "F.Paste" user)
		(15 "B.Paste" user)
		(5 "F.SilkS" user "F.Silkscreen")
		(7 "B.SilkS" user "B.Silkscreen")
		(1 "F.Mask" user)
		(3 "B.Mask" user)
		(17 "Dwgs.User" user "User.Drawings")
		(19 "Cmts.User" user "User.Comments")
		(21 "Eco1.User" user "User.Eco1")
		(23 "Eco2.User" user "User.Eco2")
		(25 "Edge.Cuts" user)
		(27 "Margin" user)
		(31 "F.CrtYd" user "F.Courtyard")
		(29 "B.CrtYd" user "B.Courtyard")
		(35 "F.Fab" user)
		(33 "B.Fab" user)
	)
	(footprint "antmicro-footprints:C_0402_1005Metric"
		(layer "B.Cu")
		(at 91.15 158.004992 90)
		(descr "Capacitor SMD 0402")
		(tags "capacitor SMD 0402")
		(property "Reference" "C148"
			(at 0 0.699 270)
			(layer "B.SilkS")
			(hide yes)
			(effects
				(font
					(size 0.7 0.7)
					(thickness 0.15)
				)
				(justify left bottom mirror)
			)
		)
		(property "Value" "C_470n_0402"
			(at -1.022927 -2.155213 270)
			(layer "B.Fab")
			(effects
				(font
					(size 0.7 0.7)
					(thickness 0.15)
				)
				(justify left bottom mirror)
			)
		)
		(property "Datasheet" "https://product.tdk.com/en/search/capacitor/ceramic/mlcc/info?part_no=C1005X5R1E474M050BB"
			(at 0 0 90)
			(layer "F.Fab")
			(hide yes)
			(effects
				(font
					(size 1.27 1.27)
					(thickness 0.15)
				)
			)
		)
		(property "Author" "Antmicro"
			(at 249.154992 66.854992 0)
			(layer "B.Fab")
			(hide yes)
			(effects
				(font
					(size 1 1)
					(thickness 0.15)
				)
				(justify mirror)
			)
		)
		(property "Dielectric" ""
			(at 249.154992 66.854992 0)
			(layer "B.Fab")
			(hide yes)
			(effects
				(font
					(size 1 1)
					(thickness 0.15)
				)
				(justify mirror)
			)
		)
		(property "License" "Apache-2.0"
			(at 249.154992 66.854992 0)
			(layer "B.Fab")
			(hide yes)
			(effects
				(font
					(size 1 1)
					(thickness 0.15)
				)
				(justify mirror)
			)
		)
		(property "MPN" "C1005X5R1E474M050BB"
			(at 249.154992 66.854992 0)
			(layer "B.Fab")
			(hide yes)
			(effects
				(font
					(size 1 1)
					(thickness 0.15)
				)
				(justify mirror)
			)
		)
		(property "Manufacturer" "TDK"
			(at 249.154992 66.854992 0)
			(layer "B.Fab")
			(hide yes)
			(effects
				(font
					(size 1 1)
					(thickness 0.15)
				)
				(justify mirror)
			)
		)
		(property "Val" "470n"
			(at 249.154992 66.854992 0)
			(layer "B.Fab")
			(hide yes)
			(effects
				(font
					(size 1 1)
					(thickness 0.15)
				)
				(justify mirror)
			)
		)
		(property "Voltage" ""
			(at 249.154992 66.854992 0)
			(layer "B.Fab")
			(hide yes)
			(effects
				(font
					(size 1 1)
					(thickness 0.15)
				)
				(justify mirror)
			)
		)
		(sheetname "/Ethernet/")
		(sheetfile "ethernet.kicad_sch")
		(attr smd)
		(fp_rect
			(start -0.9659 0.481258)
			(end 0.9649 -0.458742)
			(stroke
				(width 0.05)
				(type solid)
			)
			(fill no)
			(layer "B.CrtYd")
		)
		(fp_line
			(start 0.499 -0.248)
			(end -0.499 -0.248)
			(stroke
				(width 0.15)
				(type solid)
			)
			(layer "B.Fab")
		)
		(fp_line
			(start -0.499 -0.248)
			(end -0.499 0.25)
			(stroke
				(width 0.15)
				(type solid)
			)
			(layer "B.Fab")
		)
		(fp_line
			(start 0.499 0.25)
			(end 0.499 -0.248)
			(stroke
				(width 0.15)
				(type solid)
			)
			(layer "B.Fab")
		)
		(fp_line
			(start -0.499 0.25)
			(end 0.499 0.25)
			(stroke
				(width 0.15)
				(type solid)
			)
			(layer "B.Fab")
		)
		(pad "1" smd roundrect
			(at -0.484 0 90)
			(size 0.59 0.64)
			(layers "B.Cu" "B.Mask" "B.Paste")
			(roundrect_rratio 0.25)
			(net 199 "+1V2")
			(pintype "passive")
		)
		(pad "2" smd roundrect
			(at 0.484 0 90)
			(size 0.59 0.64)
			(layers "B.Cu" "B.Mask" "B.Paste")
			(roundrect_rratio 0.25)
			(net 1 "GND")
			(pintype "passive")
		)
	)
	(footprint "antmicro-footprints:C_0402_1005Metric"
		(layer "B.Cu")
		(at 94.061829 150.283157 90)
		(descr "Capacitor SMD 0402")
		(tags "capacitor SMD 0402")
		(property "Reference" "C140"
			(at 0 0.699 270)
			(layer "B.SilkS")
			(hide yes)
			(effects
				(font
					(size 0.7 0.7)
					(thickness 0.15)
				)
				(justify left bottom mirror)
			)
		)
		(property "Value" "C_10n_0402"
			(at -1.022927 -2.155213 270)
			(layer "B.Fab")
			(effects
				(font
					(size 0.7 0.7)
					(thickness 0.15)
				)
				(justify left bottom mirror)
			)
		)
		(property "Datasheet" "https://www.murata.com/products/productdetail?partno=GRM155R71H103KA88%23"
			(at 0 0 90)
			(layer "F.Fab")
			(hide yes)
			(effects
				(font
					(size 1.27 1.27)
					(thickness 0.15)
				)
			)
		)
		(property "Author" "Antmicro"
			(at 244.344986 56.221328 0)
			(layer "B.Fab")
			(hide yes)
			(effects
				(font
					(size 1 1)
					(thickness 0.15)
				)
				(justify mirror)
			)
		)
		(property "Dielectric" "X7R"
			(at 244.344986 56.221328 0)
			(layer "B.Fab")
			(hide yes)
			(effects
				(font
					(size 1 1)
					(thickness 0.15)
				)
				(justify mirror)
			)
		)
		(property "License" "Apache-2.0"
			(at 244.344986 56.221328 0)
			(layer "B.Fab")
			(hide yes)
			(effects
				(font
					(size 1 1)
					(thickness 0.15)
				)
				(justify mirror)
			)
		)
		(property "MPN" "GRM155R71H103KA88D"
			(at 244.344986 56.221328 0)
			(layer "B.Fab")
			(hide yes)
			(effects
				(font
					(size 1 1)
					(thickness 0.15)
				)
				(justify mirror)
			)
		)
		(property "Manufacturer" "Murata"
			(at 244.344986 56.221328 0)
			(layer "B.Fab")
			(hide yes)
			(effects
				(font
					(size 1 1)
					(thickness 0.15)
				)
				(justify mirror)
			)
		)
		(property "Val" "10n"
			(at 244.344986 56.221328 0)
			(layer "B.Fab")
			(hide yes)
			(effects
				(font
					(size 1 1)
					(thickness 0.15)
				)
				(justify mirror)
			)
		)
		(property "Voltage" "50V"
			(at 244.344986 56.221328 0)
			(layer "B.Fab")
			(hide yes)
			(effects
				(font
					(size 1 1)
					(thickness 0.15)
				)
				(justify mirror)
			)
		)
		(sheetname "/Ethernet/")
		(sheetfile "ethernet.kicad_sch")
		(attr smd)
		(fp_rect
			(start -0.9659 0.481258)
			(end 0.9649 -0.458742)
			(stroke
				(width 0.05)
				(type solid)
			)
			(fill no)
			(layer "B.CrtYd")
		)
		(fp_line
			(start 0.499 -0.248)
			(end -0.499 -0.248)
			(stroke
				(width 0.15)
				(type solid)
			)
			(layer "B.Fab")
		)
		(fp_line
			(start -0.499 -0.248)
			(end -0.499 0.25)
			(stroke
				(width 0.15)
				(type solid)
			)
			(layer "B.Fab")
		)
		(fp_line
			(start 0.499 0.25)
			(end 0.499 -0.248)
			(stroke
				(width 0.15)
				(type solid)
			)
			(layer "B.Fab")
		)
		(fp_line
			(start -0.499 0.25)
			(end 0.499 0.25)
			(stroke
				(width 0.15)
				(type solid)
			)
			(layer "B.Fab")
		)
		(pad "1" smd roundrect
			(at -0.484 0 90)
			(size 0.59 0.64)
			(layers "B.Cu" "B.Mask" "B.Paste")
			(roundrect_rratio 0.25)
			(net 132 "/Ethernet/AVDDL")
			(pintype "passive")
		)
		(pad "2" smd roundrect
			(at 0.484 0 90)
			(size 0.59 0.64)
			(layers "B.Cu" "B.Mask" "B.Paste")
			(roundrect_rratio 0.25)
			(net 1 "GND")
			(pintype "passive")
		)
	)
	(footprint "antmicro-footprints:C_0402_1005Metric"
		(layer "B.Cu")
		(at 94.308672 158.004992 90)
		(descr "Capacitor SMD 0402")
		(tags "capacitor SMD 0402")
		(property "Reference" "C141"
			(at 0 0.699 270)
			(layer "B.SilkS")
			(hide yes)
			(effects
				(font
					(size 0.7 0.7)
					(thickness 0.15)
				)
				(justify left bottom mirror)
			)
		)
		(property "Value" "C_10n_0402"
			(at -1.022927 -2.155213 270)
			(layer "B.Fab")
			(effects
				(font
					(size 0.7 0.7)
					(thickness 0.15)
				)
				(justify left bottom mirror)
			)
		)
		(property "Datasheet" "https://www.murata.com/products/productdetail?partno=GRM155R71H103KA88%23"
			(at 0 0 90)
			(layer "F.Fab")
			(hide yes)
			(effects
				(font
					(size 1.27 1.27)
					(thickness 0.15)
				)
			)
		)
		(property "Author" "Antmicro"
			(at 252.313664 63.69632 0)
			(layer "B.Fab")
			(hide yes)
			(effects
				(font
					(size 1 1)
					(thickness 0.15)
				)
				(justify mirror)
			)
		)
		(property "Dielectric" "X7R"
			(at 252.313664 63.69632 0)
			(layer "B.Fab")
			(hide yes)
			(effects
				(font
					(size 1 1)
					(thickness 0.15)
				)
				(justify mirror)
			)
		)
		(property "License" "Apache-2.0"
			(at 252.313664 63.69632 0)
			(layer "B.Fab")
			(hide yes)
			(effects
				(font
					(size 1 1)
					(thickness 0.15)
				)
				(justify mirror)
			)
		)
		(property "MPN" "GRM155R71H103KA88D"
			(at 252.313664 63.69632 0)
			(layer "B.Fab")
			(hide yes)
			(effects
				(font
					(size 1 1)
					(thickness 0.15)
				)
				(justify mirror)
			)
		)
		(property "Manufacturer" "Murata"
			(at 252.313664 63.69632 0)
			(layer "B.Fab")
			(hide yes)
			(effects
				(font
					(size 1 1)
					(thickness 0.15)
				)
				(justify mirror)
			)
		)
		(property "Val" "10n"
			(at 252.313664 63.69632 0)
			(layer "B.Fab")
			(hide yes)
			(effects
				(font
					(size 1 1)
					(thickness 0.15)
				)
				(justify mirror)
			)
		)
		(property "Voltage" "50V"
			(at 252.313664 63.69632 0)
			(layer "B.Fab")
			(hide yes)
			(effects
				(font
					(size 1 1)
					(thickness 0.15)
				)
				(justify mirror)
			)
		)
		(sheetname "/Ethernet/")
		(sheetfile "ethernet.kicad_sch")
		(attr smd)
		(fp_rect
			(start -0.9659 0.481258)
			(end 0.9649 -0.458742)
			(stroke
				(width 0.05)
				(type solid)
			)
			(fill no)
			(layer "B.CrtYd")
		)
		(fp_line
			(start 0.499 -0.248)
			(end -0.499 -0.248)
			(stroke
				(width 0.15)
				(type solid)
			)
			(layer "B.Fab")
		)
		(fp_line
			(start -0.499 -0.248)
			(end -0.499 0.25)
			(stroke
				(width 0.15)
				(type solid)
			)
			(layer "B.Fab")
		)
		(fp_line
			(start 0.499 0.25)
			(end 0.499 -0.248)
			(stroke
				(width 0.15)
				(type solid)
			)
			(layer "B.Fab")
		)
		(fp_line
			(start -0.499 0.25)
			(end 0.499 0.25)
			(stroke
				(width 0.15)
				(type solid)
			)
			(layer "B.Fab")
		)
		(pad "1" smd roundrect
			(at -0.484 0 90)
			(size 0.59 0.64)
			(layers "B.Cu" "B.Mask" "B.Paste")
			(roundrect_rratio 0.25)
			(net 200 "+3V3")
			(pintype "passive")
		)
		(pad "2" smd roundrect
			(at 0.484 0 90)
			(size 0.59 0.64)
			(layers "B.Cu" "B.Mask" "B.Paste")
			(roundrect_rratio 0.25)
			(net 1 "GND")
			(pintype "passive")
		)
	)
	(footprint "antmicro-footprints:C_0402_1005Metric"
		(layer "B.Cu")
		(at 97.886829 150.808157)
		(descr "Capacitor SMD 0402")
		(tags "capacitor SMD 0402")
		(property "Reference" "C152"
			(at 0 0.699 180)
			(layer "B.SilkS")
			(hide yes)
			(effects
				(font
					(size 0.7 0.7)
					(thickness 0.15)
				)
				(justify left bottom mirror)
			)
		)
		(property "Value" "C_4u7_0402"
			(at -1.022927 -2.155213 180)
			(layer "B.Fab")
			(effects
				(font
					(size 0.7 0.7)
					(thickness 0.15)
				)
				(justify left bottom mirror)
			)
		)
		(property "Datasheet" "https://www.murata.com/products/productdetail?partno=GRM155R61A475MEAA%23"
			(at 0 0 0)
			(layer "F.Fab")
			(hide yes)
			(effects
				(font
					(size 1.27 1.27)
					(thickness 0.15)
				)
			)
		)
		(property "Author" "Antmicro"
			(at 0 0 0)
			(layer "B.Fab")
			(hide yes)
			(effects
				(font
					(size 1 1)
					(thickness 0.15)
				)
				(justify mirror)
			)
		)
		(property "Dielectric" ""
			(at 0 0 0)
			(layer "B.Fab")
			(hide yes)
			(effects
				(font
					(size 1 1)
					(thickness 0.15)
				)
				(justify mirror)
			)
		)
		(property "License" "Apache-2.0"
			(at 0 0 0)
			(layer "B.Fab")
			(hide yes)
			(effects
				(font
					(size 1 1)
					(thickness 0.15)
				)
				(justify mirror)
			)
		)
		(property "MPN" "GRM155R61A475MEAAD"
			(at 0 0 0)
			(layer "B.Fab")
			(hide yes)
			(effects
				(font
					(size 1 1)
					(thickness 0.15)
				)
				(justify mirror)
			)
		)
		(property "Manufacturer" "Murata"
			(at 0 0 0)
			(layer "B.Fab")
			(hide yes)
			(effects
				(font
					(size 1 1)
					(thickness 0.15)
				)
				(justify mirror)
			)
		)
		(property "Val" "4u7"
			(at 0 0 0)
			(layer "B.Fab")
			(hide yes)
			(effects
				(font
					(size 1 1)
					(thickness 0.15)
				)
				(justify mirror)
			)
		)
		(property "Voltage" ""
			(at 0 0 0)
			(layer "B.Fab")
			(hide yes)
			(effects
				(font
					(size 1 1)
					(thickness 0.15)
				)
				(justify mirror)
			)
		)
		(sheetname "/Ethernet/")
		(sheetfile "ethernet.kicad_sch")
		(attr smd)
		(fp_rect
			(start -0.9659 0.481258)
			(end 0.9649 -0.458742)
			(stroke
				(width 0.05)
				(type solid)
			)
			(fill no)
			(layer "B.CrtYd")
		)
		(fp_line
			(start -0.499 -0.248)
			(end -0.499 0.25)
			(stroke
				(width 0.15)
				(type solid)
			)
			(layer "B.Fab")
		)
		(fp_line
			(start -0.499 0.25)
			(end 0.499 0.25)
			(stroke
				(width 0.15)
				(type solid)
			)
			(layer "B.Fab")
		)
		(fp_line
			(start 0.499 -0.248)
			(end -0.499 -0.248)
			(stroke
				(width 0.15)
				(type solid)
			)
			(layer "B.Fab")
		)
		(fp_line
			(start 0.499 0.25)
			(end 0.499 -0.248)
			(stroke
				(width 0.15)
				(type solid)
			)
			(layer "B.Fab")
		)
		(pad "1" smd roundrect
			(at -0.484 0)
			(size 0.59 0.64)
			(layers "B.Cu" "B.Mask" "B.Paste")
			(roundrect_rratio 0.25)
			(net 134 "/Ethernet/AVDDH")
			(pintype "passive")
		)
		(pad "2" smd roundrect
			(at 0.484 0)
			(size 0.59 0.64)
			(layers "B.Cu" "B.Mask" "B.Paste")
			(roundrect_rratio 0.25)
			(net 1 "GND")
			(pintype "passive")
		)
	)
	(footprint "antmicro-footprints:C_0402_1005Metric"
		(layer "B.Cu")
		(at 91.5 150.283157 90)
		(descr "Capacitor SMD 0402")
		(tags "capacitor SMD 0402")
		(property "Reference" "C136"
			(at 0 0.699 270)
			(layer "B.SilkS")
			(hide yes)
			(effects
				(font
					(size 0.7 0.7)
					(thickness 0.15)
				)
				(justify left bottom mirror)
			)
		)
		(property "Value" "C_10n_0402"
			(at -1.022927 -2.155213 270)
			(layer "B.Fab")
			(effects
				(font
					(size 0.7 0.7)
					(thickness 0.15)
				)
				(justify left bottom mirror)
			)
		)
		(property "Datasheet" "https://www.murata.com/products/productdetail?partno=GRM155R71H103KA88%23"
			(at 0 0 90)
			(layer "F.Fab")
			(hide yes)
			(effects
				(font
					(size 1.27 1.27)
					(thickness 0.15)
				)
			)
		)
		(property "Author" "Antmicro"
			(at 241.783157 58.783157 0)
			(layer "B.Fab")
			(hide yes)
			(effects
				(font
					(size 1 1)
					(thickness 0.15)
				)
				(justify mirror)
			)
		)
		(property "Dielectric" "X7R"
			(at 241.783157 58.783157 0)
			(layer "B.Fab")
			(hide yes)
			(effects
				(font
					(size 1 1)
					(thickness 0.15)
				)
				(justify mirror)
			)
		)
		(property "License" "Apache-2.0"
			(at 241.783157 58.783157 0)
			(layer "B.Fab")
			(hide yes)
			(effects
				(font
					(size 1 1)
					(thickness 0.15)
				)
				(justify mirror)
			)
		)
		(property "MPN" "GRM155R71H103KA88D"
			(at 241.783157 58.783157 0)
			(layer "B.Fab")
			(hide yes)
			(effects
				(font
					(size 1 1)
					(thickness 0.15)
				)
				(justify mirror)
			)
		)
		(property "Manufacturer" "Murata"
			(at 241.783157 58.783157 0)
			(layer "B.Fab")
			(hide yes)
			(effects
				(font
					(size 1 1)
					(thickness 0.15)
				)
				(justify mirror)
			)
		)
		(property "Val" "10n"
			(at 241.783157 58.783157 0)
			(layer "B.Fab")
			(hide yes)
			(effects
				(font
					(size 1 1)
					(thickness 0.15)
				)
				(justify mirror)
			)
		)
		(property "Voltage" "50V"
			(at 241.783157 58.783157 0)
			(layer "B.Fab")
			(hide yes)
			(effects
				(font
					(size 1 1)
					(thickness 0.15)
				)
				(justify mirror)
			)
		)
		(sheetname "/Ethernet/")
		(sheetfile "ethernet.kicad_sch")
		(attr smd)
		(fp_rect
			(start -0.9659 0.481258)
			(end 0.9649 -0.458742)
			(stroke
				(width 0.05)
				(type solid)
			)
			(fill no)
			(layer "B.CrtYd")
		)
		(fp_line
			(start 0.499 -0.248)
			(end -0.499 -0.248)
			(stroke
				(width 0.15)
				(type solid)
			)
			(layer "B.Fab")
		)
		(fp_line
			(start -0.499 -0.248)
			(end -0.499 0.25)
			(stroke
				(width 0.15)
				(type solid)
			)
			(layer "B.Fab")
		)
		(fp_line
			(start 0.499 0.25)
			(end 0.499 -0.248)
			(stroke
				(width 0.15)
				(type solid)
			)
			(layer "B.Fab")
		)
		(fp_line
			(start -0.499 0.25)
			(end 0.499 0.25)
			(stroke
				(width 0.15)
				(type solid)
			)
			(layer "B.Fab")
		)
		(pad "1" smd roundrect
			(at -0.484 0 90)
			(size 0.59 0.64)
			(layers "B.Cu" "B.Mask" "B.Paste")
			(roundrect_rratio 0.25)
			(net 132 "/Ethernet/AVDDL")
			(pintype "passive")
		)
		(pad "2" smd roundrect
			(at 0.484 0 90)
			(size 0.59 0.64)
			(layers "B.Cu" "B.Mask" "B.Paste")
			(roundrect_rratio 0.25)
			(net 1 "GND")
			(pintype "passive")
		)
	)
	(footprint "antmicro-footprints:C_0402_1005Metric"
		(layer "B.Cu")
		(at 98.1 155.2)
		(descr "Capacitor SMD 0402")
		(tags "capacitor SMD 0402")
		(property "Reference" "C144"
			(at 0 0.699 180)
			(layer "B.SilkS")
			(hide yes)
			(effects
				(font
					(size 0.7 0.7)
					(thickness 0.15)
				)
				(justify left bottom mirror)
			)
		)
		(property "Value" "C_10n_0402"
			(at -1.022927 -2.155213 180)
			(layer "B.Fab")
			(effects
				(font
					(size 0.7 0.7)
					(thickness 0.15)
				)
				(justify left bottom mirror)
			)
		)
		(property "Datasheet" "https://www.murata.com/products/productdetail?partno=GRM155R71H103KA88%23"
			(at 0 0 0)
			(layer "F.Fab")
			(hide yes)
			(effects
				(font
					(size 1.27 1.27)
					(thickness 0.15)
				)
			)
		)
		(property "Author" "Antmicro"
			(at 0 0 0)
			(layer "B.Fab")
			(hide yes)
			(effects
				(font
					(size 1 1)
					(thickness 0.15)
				)
				(justify mirror)
			)
		)
		(property "Dielectric" "X7R"
			(at 0 0 0)
			(layer "B.Fab")
			(hide yes)
			(effects
				(font
					(size 1 1)
					(thickness 0.15)
				)
				(justify mirror)
			)
		)
		(property "License" "Apache-2.0"
			(at 0 0 0)
			(layer "B.Fab")
			(hide yes)
			(effects
				(font
					(size 1 1)
					(thickness 0.15)
				)
				(justify mirror)
			)
		)
		(property "MPN" "GRM155R71H103KA88D"
			(at 0 0 0)
			(layer "B.Fab")
			(hide yes)
			(effects
				(font
					(size 1 1)
					(thickness 0.15)
				)
				(justify mirror)
			)
		)
		(property "Manufacturer" "Murata"
			(at 0 0 0)
			(layer "B.Fab")
			(hide yes)
			(effects
				(font
					(size 1 1)
					(thickness 0.15)
				)
				(justify mirror)
			)
		)
		(property "Val" "10n"
			(at 0 0 0)
			(layer "B.Fab")
			(hide yes)
			(effects
				(font
					(size 1 1)
					(thickness 0.15)
				)
				(justify mirror)
			)
		)
		(property "Voltage" "50V"
			(at 0 0 0)
			(layer "B.Fab")
			(hide yes)
			(effects
				(font
					(size 1 1)
					(thickness 0.15)
				)
				(justify mirror)
			)
		)
		(sheetname "/Ethernet/")
		(sheetfile "ethernet.kicad_sch")
		(attr smd)
		(fp_rect
			(start -0.9659 0.481258)
			(end 0.9649 -0.458742)
			(stroke
				(width 0.05)
				(type solid)
			)
			(fill no)
			(layer "B.CrtYd")
		)
		(fp_line
			(start -0.499 -0.248)
			(end -0.499 0.25)
			(stroke
				(width 0.15)
				(type solid)
			)
			(layer "B.Fab")
		)
		(fp_line
			(start -0.499 0.25)
			(end 0.499 0.25)
			(stroke
				(width 0.15)
				(type solid)
			)
			(layer "B.Fab")
		)
		(fp_line
			(start 0.499 -0.248)
			(end -0.499 -0.248)
			(stroke
				(width 0.15)
				(type solid)
			)
			(layer "B.Fab")
		)
		(fp_line
			(start 0.499 0.25)
			(end 0.499 -0.248)
			(stroke
				(width 0.15)
				(type solid)
			)
			(layer "B.Fab")
		)
		(pad "1" smd roundrect
			(at -0.484 0)
			(size 0.59 0.64)
			(layers "B.Cu" "B.Mask" "B.Paste")
			(roundrect_rratio 0.25)
			(net 200 "+3V3")
			(pintype "passive")
		)
		(pad "2" smd roundrect
			(at 0.484 0)
			(size 0.59 0.64)
			(layers "B.Cu" "B.Mask" "B.Paste")
			(roundrect_rratio 0.25)
			(net 1 "GND")
			(pintype "passive")
		)
	)
)
